# BASEBOARD_FAB2 (Tioga Pass) — schematic netlist excerpt (pin names and nets, part order shuffled) for the footprints in the layout excerpt that follows; sources: Cadence DE-HDL packaged netlist, KiCad conversion of Wiwynn_Tioga_Pass_MB.brd

C22W31  SC22U16V5MX-4-GP  20%  pkg SMD-BCG5  page 212 : \1\ = VR_FET_SW_P12V_STBY_PVCCIO_CPU0 ; \2\ = GND
C6N8  CAP  10UF 16V 10% X6S  pkg 0805  page 202 : A = VR_FET_SW_P12V_STBY_PVCCIN_CPU0 ; B = GND
C3P7  CAP_A  0.1UF 16V 10% X7R  pkg 0402V  page 211 : A = VR_PVCCIO_CPU0_VDD ; B = GND

(kicad_pcb
	(version 20260206)
	(generator "pcbnew")
	(generator_version "10.0")
	(general
		(thickness 1.6)
		(legacy_teardrops no)
	)
	(paper "A4")
	(title_block
		(title "Wiwynn_Tioga_Pass_MB.brd")
		(comment 1 "Tioga Pass / footprints 4303-4305 of 4770")
	)
	(layers
		(0 "F.Cu" signal "TOP")
		(4 "In1.Cu" signal "L2GND")
		(6 "In2.Cu" signal "L3")
		(8 "In3.Cu" signal "L4GND")
		(10 "In4.Cu" signal "L5")
		(12 "In5.Cu" signal "L6GND")
		(14 "In6.Cu" signal "L7VCC")
		(16 "In7.Cu" signal "L8VCC")
		(18 "In8.Cu" signal "L9GND")
		(20 "In9.Cu" signal "L10")
		(22 "In10.Cu" signal "L11GND")
		(24 "In11.Cu" signal "L12")
		(26 "In12.Cu" signal "L13GND")
		(2 "B.Cu" signal "BOTTOM")
		(9 "F.Adhes" user "F.Adhesive")
		(11 "B.Adhes" user "B.Adhesive")
		(13 "F.Paste" user "Package Geometry/Pastemask Top")
		(15 "B.Paste" user "Package Geometry/Pastemask Bottom")
		(5 "F.SilkS" user "Ref Des/Silkscreen Top")
		(7 "B.SilkS" user "Ref Des/Silkscreen Bottom")
		(1 "F.Mask" user "Board Geometry/Soldermask Top")
		(3 "B.Mask" user "Board Geometry/Soldermask Bottom")
		(17 "Dwgs.User" user "User.Drawings")
		(19 "Cmts.User" user "User.Comments")
		(21 "Eco1.User" user "User.Eco1")
		(23 "Eco2.User" user "User.Eco2")
		(25 "Edge.Cuts" user "Board Geometry/Outline")
		(27 "Margin" user)
		(31 "F.CrtYd" user "Package Geometry/Place Bound Top")
		(29 "B.CrtYd" user "Package Geometry/Place Bound Bottom")
		(35 "F.Fab" user "Ref Des/Assembly Top")
		(33 "B.Fab" user "Ref Des/Assembly Bottom")
	)
	(footprint ""
		(layer "B.Cu")
		(at 356.08768 -94.072202 90)
		(property "Reference" "C22W31"
			(at 0 0 90)
			(layer "B.SilkS")
			(hide yes)
			(effects
				(font
					(size 1.27 1.27)
				)
				(justify mirror)
			)
		)
		(property "Value" "*"
			(at 0.0762 -6.2357 90)
			(unlocked yes)
			(layer "B.Fab")
			(hide yes)
			(effects
				(font
					(size 1.27 1.016)
					(thickness 0.1524)
				)
				(justify mirror)
			)
		)
		(property "Device Type" "SC22U16V5MX-4-GP_SMD-BCG5-SC22A"
			(at 0.0762 -8.2677 90)
			(unlocked yes)
			(layer "B.Fab")
			(hide yes)
			(effects
				(font
					(size 1.27 1.016)
					(thickness 0.1524)
				)
				(justify mirror)
			)
		)
		(duplicate_pad_numbers_are_jumpers no)
		(fp_line
			(start -0.635 0)
			(end 0.635 0)
			(stroke
				(width 0.508)
				(type default)
			)
			(layer "B.SilkS")
		)
		(fp_rect
			(start 0.9652 1.778)
			(end -0.9652 -1.778)
			(stroke
				(width 0)
				(type default)
			)
			(fill no)
			(layer "B.CrtYd")
		)
		(fp_poly
			(pts
				(xy 0.9652 -1.778) (xy -0.9652 -1.778) (xy -0.9652 1.778) (xy 0.9652 1.778)
			)
			(stroke
				(width 0)
				(type default)
			)
			(fill no)
			(layer "B.Fab")
		)
		(pad "1" smd rect
			(at 0 -0.9652 270)
			(size 1.397 1.143)
			(layers "B.Cu" "B.Mask" "B.Paste")
			(net "VR_FET_SW_P12V_STBY_PVCCIO_CPU0")
		)
		(pad "2" smd rect
			(at 0 0.9652 270)
			(size 1.397 1.143)
			(layers "B.Cu" "B.Mask" "B.Paste")
			(net "GND")
		)
	)
	(footprint ""
		(layer "B.Cu")
		(at 351.2312 -85.1408 90)
		(property "Reference" "C3P7"
			(at 0 0 90)
			(layer "B.SilkS")
			(hide yes)
			(effects
				(font
					(size 1.27 1.27)
				)
				(justify mirror)
			)
		)
		(property "Value" ""
			(at 0 0 90)
			(layer "B.Fab")
			(effects
				(font
					(size 1.27 1.27)
				)
				(justify mirror)
			)
		)
		(duplicate_pad_numbers_are_jumpers no)
		(fp_poly
			(pts
				(xy -0.3048 -0.1016) (xy -0.3048 0.9906) (xy 0.3048 0.9906) (xy 0.3048 -0.1016)
			)
			(stroke
				(width 0)
				(type default)
			)
			(fill no)
			(layer "B.CrtYd")
		)
		(fp_line
			(start 0.3048 -0.1016)
			(end 0.3048 0.9906)
			(stroke
				(width 0.1)
				(type default)
			)
			(layer "B.Fab")
		)
		(fp_line
			(start -0.3048 -0.1016)
			(end 0.3048 -0.1016)
			(stroke
				(width 0.1)
				(type default)
			)
			(layer "B.Fab")
		)
		(fp_line
			(start 0.3048 0.9906)
			(end -0.3048 0.9906)
			(stroke
				(width 0.1)
				(type default)
			)
			(layer "B.Fab")
		)
		(fp_line
			(start -0.3048 0.9906)
			(end -0.3048 -0.1016)
			(stroke
				(width 0.1)
				(type default)
			)
			(layer "B.Fab")
		)
		(pad "1" smd rect
			(at 0 0 270)
			(size 0.508 0.508)
			(layers "B.Cu" "B.Mask" "B.Paste")
			(net "VR_PVCCIO_CPU0_VDD")
		)
		(pad "2" smd rect
			(at 0 0.889 270)
			(size 0.508 0.508)
			(layers "B.Cu" "B.Mask" "B.Paste")
			(net "GND")
		)
		(zone
			(layer "B.Cu")
			(hatch none 0.5)
			(connect_pads
				(clearance 0)
			)
			(min_thickness 0.25)
			(keepout
				(tracks allowed)
				(vias not_allowed)
				(pads allowed)
				(copperpour not_allowed)
				(footprints allowed)
			)
			(placement
				(enabled no)
				(sheetname "")
			)
			(fill
				(thermal_gap 0.5)
				(thermal_bridge_width 0.5)
				(island_removal_mode 0)
			)
			(polygon
				(pts
					(xy 351.4852 -85.3948) (xy 351.4852 -84.8868) (xy 351.8662 -84.8868) (xy 351.8662 -85.3948)
				)
			)
		)
		(zone
			(layer "B.Cu")
			(hatch none 0.5)
			(connect_pads
				(clearance 0)
			)
			(min_thickness 0.25)
			(keepout
				(tracks not_allowed)
				(vias allowed)
				(pads allowed)
				(copperpour not_allowed)
				(footprints allowed)
			)
			(placement
				(enabled no)
				(sheetname "")
			)
			(fill
				(thermal_gap 0.5)
				(thermal_bridge_width 0.5)
				(island_removal_mode 0)
			)
			(polygon
				(pts
					(xy 351.8662 -85.3948) (xy 351.8662 -84.8868) (xy 351.4852 -84.8868) (xy 351.4852 -85.3948)
				)
			)
		)
	)
	(footprint ""
		(layer "B.Cu")
		(at 197.848728 -92.489782 90)
		(property "Reference" "C6N8"
			(at 0 0 90)
			(layer "B.SilkS")
			(hide yes)
			(effects
				(font
					(size 1.27 1.27)
				)
				(justify mirror)
			)
		)
		(property "Value" ""
			(at 0 0 90)
			(layer "B.Fab")
			(effects
				(font
					(size 1.27 1.27)
				)
				(justify mirror)
			)
		)
		(duplicate_pad_numbers_are_jumpers no)
		(fp_rect
			(start -0.7239 -0.2159)
			(end 0.7239 1.9939)
			(stroke
				(width 0)
				(type default)
			)
			(fill no)
			(layer "B.CrtYd")
		)
		(fp_line
			(start 0.7239 -0.2159)
			(end 0.7239 1.9939)
			(stroke
				(width 0.1)
				(type default)
			)
			(layer "B.Fab")
		)
		(fp_line
			(start -0.7239 -0.2159)
			(end 0.7239 -0.2159)
			(stroke
				(width 0.1)
				(type default)
			)
			(layer "B.Fab")
		)
		(fp_line
			(start 0.7239 1.9939)
			(end -0.7239 1.9939)
			(stroke
				(width 0.1)
				(type default)
			)
			(layer "B.Fab")
		)
		(fp_line
			(start -0.7239 1.9939)
			(end -0.7239 -0.2159)
			(stroke
				(width 0.1)
				(type default)
			)
			(layer "B.Fab")
		)
		(pad "1" smd rect
			(at 0 0 270)
			(size 1.27 1.016)
			(layers "B.Cu" "B.Mask" "B.Paste")
			(net "VR_FET_SW_P12V_STBY_PVCCIN_CPU0")
		)
		(pad "2" smd rect
			(at 0 1.778 270)
			(size 1.27 1.016)
			(layers "B.Cu" "B.Mask" "B.Paste")
			(net "GND")
		)
		(zone
			(layer "B.Cu")
			(hatch none 0.5)
			(connect_pads
				(clearance 0)
			)
			(min_thickness 0.25)
			(keepout
				(tracks not_allowed)
				(vias allowed)
				(pads allowed)
				(copperpour not_allowed)
				(footprints allowed)
			)
			(placement
				(enabled no)
				(sheetname "")
			)
			(fill
				(thermal_gap 0.5)
				(thermal_bridge_width 0.5)
				(island_removal_mode 0)
			)
			(polygon
				(pts
					(xy 198.356728 -91.854782) (xy 199.118728 -91.854782) (xy 199.118728 -93.124782) (xy 198.356728 -93.124782)
				)
			)
		)
	)
)
